# T6G (Grand Teton) — schematic netlist excerpt (pin names and nets, part order shuffled) for the footprints in the layout excerpt that follows; sources: Cadence DE-HDL packaged netlist, KiCad conversion of 04192023_DAF0TMB3IC0_F0TG_MB_C_brd_V02_OCP.brd

PL15  Q_INDUCTOR4P_14  150NH IND  pkg L_TLM117513Q-151QL_11X7-5XA  page 203
  \1\  = SW_PVDDCR_CPU1_P0_SW5
  \2\  = IND_CPU1_P0_CPL6
  \3\  = IND_CPU1_P0_CPL5
  \4\  = PVDDCR_CPU1_P0

U290  MOSFET_NCH_GDS_ESD_PROTECTED  2N7002K IC  pkg SOT23_GDSXC  page 268
  D  = HSC_EN
  G  = PDB_PRSNT_R_N
  S  = GND

(kicad_pcb
	(version 20260206)
	(generator "pcbnew")
	(generator_version "10.0")
	(general
		(thickness 1.6)
		(legacy_teardrops no)
	)
	(paper "A4")
	(title_block
		(title "04192023_DAF0TMB3IC0_F0TG_MB_C_brd_V02_OCP.brd")
		(comment 1 "Grand Teton / footprints 1171-1172 of 8354")
	)
	(layers
		(0 "F.Cu" signal "TOP")
		(4 "In1.Cu" signal "GND")
		(6 "In2.Cu" signal "IN1")
		(8 "In3.Cu" signal "GND1")
		(10 "In4.Cu" signal "IN2")
		(12 "In5.Cu" signal "GND2")
		(14 "In6.Cu" signal "IN3")
		(16 "In7.Cu" signal "GND3")
		(18 "In8.Cu" signal "VCC")
		(20 "In9.Cu" signal "VCC1")
		(22 "In10.Cu" signal "GND4")
		(24 "In11.Cu" signal "IN4")
		(26 "In12.Cu" signal "GND5")
		(28 "In13.Cu" signal "IN5")
		(30 "In14.Cu" signal "GND6")
		(32 "In15.Cu" signal "IN6")
		(34 "In16.Cu" signal "GND7")
		(2 "B.Cu" signal "BOTTOM")
		(9 "F.Adhes" user "F.Adhesive")
		(11 "B.Adhes" user "B.Adhesive")
		(13 "F.Paste" user "Package Geometry/Pastemask Top")
		(15 "B.Paste" user "Package Geometry/Pastemask Bottom")
		(5 "F.SilkS" user "Ref Des/Silkscreen Top")
		(7 "B.SilkS" user "Ref Des/Silkscreen Bottom")
		(1 "F.Mask" user "Board Geometry/Soldermask Top")
		(3 "B.Mask" user "Board Geometry/Soldermask Bottom")
		(17 "Dwgs.User" user "User.Drawings")
		(19 "Cmts.User" user "User.Comments")
		(21 "Eco1.User" user "User.Eco1")
		(23 "Eco2.User" user "User.Eco2")
		(25 "Edge.Cuts" user "Board Geometry/Outline")
		(27 "Margin" user)
		(31 "F.CrtYd" user "Package Geometry/Place Bound Top")
		(29 "B.CrtYd" user "Package Geometry/Place Bound Bottom")
		(35 "F.Fab" user "Ref Des/Assembly Top")
		(33 "B.Fab" user "Ref Des/Assembly Bottom")
	)
	(footprint ""
		(layer "F.Cu")
		(at 343.43086 -325.670926)
		(property "Reference" "PL15"
			(at -3.115056 -16.014446 0)
			(unlocked yes)
			(layer "F.SilkS")
			(effects
				(font
					(size 0.7874 0.5842)
					(thickness 0.1524)
				)
				(justify left)
			)
		)
		(property "Value" ""
			(at 0 0 0)
			(layer "F.Fab")
			(effects
				(font
					(size 1.27 1.27)
				)
			)
		)
		(duplicate_pad_numbers_are_jumpers no)
		(fp_line
			(start -3.750056 -5.500116)
			(end -2.393442 -5.500116)
			(stroke
				(width 0.1524)
				(type default)
			)
			(layer "F.SilkS")
		)
		(fp_line
			(start -3.750056 5.500116)
			(end -3.750056 -5.500116)
			(stroke
				(width 0.1524)
				(type default)
			)
			(layer "F.SilkS")
		)
		(fp_line
			(start -2.393442 5.500116)
			(end -3.750056 5.500116)
			(stroke
				(width 0.1524)
				(type default)
			)
			(layer "F.SilkS")
		)
		(fp_line
			(start 2.393442 5.500116)
			(end 3.750056 5.500116)
			(stroke
				(width 0.1524)
				(type default)
			)
			(layer "F.SilkS")
		)
		(fp_line
			(start 3.750056 -5.500116)
			(end 2.393442 -5.500116)
			(stroke
				(width 0.1524)
				(type default)
			)
			(layer "F.SilkS")
		)
		(fp_line
			(start 3.750056 5.500116)
			(end 3.750056 -5.500116)
			(stroke
				(width 0.1524)
				(type default)
			)
			(layer "F.SilkS")
		)
		(fp_poly
			(pts
				(xy -3.9116 -4.249928) (xy -4.3434 -4.034028) (xy -4.3434 -4.465828)
			)
			(stroke
				(width 0)
				(type default)
			)
			(fill yes)
			(layer "F.SilkS")
		)
		(fp_line
			(start -3.750056 -5.500116)
			(end -3.750056 5.500116)
			(stroke
				(width 0.1)
				(type default)
			)
			(layer "F.Fab")
		)
		(fp_line
			(start -3.750056 5.500116)
			(end 3.750056 5.500116)
			(stroke
				(width 0.1)
				(type default)
			)
			(layer "F.Fab")
		)
		(fp_line
			(start 3.750056 -5.500116)
			(end -3.750056 -5.500116)
			(stroke
				(width 0.1)
				(type default)
			)
			(layer "F.Fab")
		)
		(fp_line
			(start 3.750056 5.500116)
			(end 3.750056 -5.500116)
			(stroke
				(width 0.1)
				(type default)
			)
			(layer "F.Fab")
		)
		(fp_poly
			(pts
				(xy -4.9276 -4.757928) (xy -4.9276 -3.741928) (xy -3.9116 -4.249928)
			)
			(stroke
				(width 0)
				(type default)
			)
			(fill yes)
			(layer "F.Fab")
		)
		(pad "1" smd rect
			(at 0 -4.249928 270)
			(size 2.413 4.5212)
			(layers "F.Cu" "F.Mask" "F.Paste")
			(net "SW_PVDDCR_CPU1_P0_SW5")
		)
		(pad "2" smd rect
			(at 0 -1.175004 270)
			(size 1.3716 4.5212)
			(layers "F.Cu" "F.Mask" "F.Paste")
			(net "IND_CPU1_P0_CPL6")
		)
		(pad "3" smd rect
			(at 0 1.175004 270)
			(size 1.3716 4.5212)
			(layers "F.Cu" "F.Mask" "F.Paste")
			(net "IND_CPU1_P0_CPL5")
		)
		(pad "4" smd rect
			(at 0 4.249928 270)
			(size 2.413 4.5212)
			(layers "F.Cu" "F.Mask" "F.Paste")
			(net "PVDDCR_CPU1_P0")
		)
	)
	(footprint ""
		(layer "F.Cu")
		(at 267.869924 -419.648386 -90)
		(property "Reference" "U290"
			(at 3.294888 1.383538 0)
			(unlocked yes)
			(layer "F.SilkS")
			(effects
				(font
					(size 0.7874 0.5842)
					(thickness 0.1524)
				)
				(justify left)
			)
		)
		(property "Value" ""
			(at 0 0 270)
			(layer "F.Fab")
			(effects
				(font
					(size 1.27 1.27)
				)
			)
		)
		(duplicate_pad_numbers_are_jumpers no)
		(fp_line
			(start -1.603248 1.500124)
			(end -1.603248 -1.500124)
			(stroke
				(width 0.1524)
				(type default)
			)
			(layer "F.SilkS")
		)
		(fp_line
			(start 1.603248 1.500124)
			(end -1.603248 1.500124)
			(stroke
				(width 0.1524)
				(type default)
			)
			(layer "F.SilkS")
		)
		(fp_line
			(start -1.603248 -1.500124)
			(end 1.603248 -1.500124)
			(stroke
				(width 0.1524)
				(type default)
			)
			(layer "F.SilkS")
		)
		(fp_line
			(start 1.603248 -1.500124)
			(end 1.603248 1.500124)
			(stroke
				(width 0.1524)
				(type default)
			)
			(layer "F.SilkS")
		)
		(fp_line
			(start -0.700024 1.500124)
			(end 0.700024 1.500124)
			(stroke
				(width 0.1)
				(type default)
			)
			(layer "F.Fab")
		)
		(fp_line
			(start 0.700024 1.500124)
			(end 0.700024 0.219964)
			(stroke
				(width 0.1)
				(type default)
			)
			(layer "F.Fab")
		)
		(fp_line
			(start -1.249934 1.169924)
			(end -0.700024 1.169924)
			(stroke
				(width 0.1)
				(type default)
			)
			(layer "F.Fab")
		)
		(fp_line
			(start -0.700024 1.169924)
			(end -0.700024 1.500124)
			(stroke
				(width 0.1)
				(type default)
			)
			(layer "F.Fab")
		)
		(fp_line
			(start -1.249934 0.729996)
			(end -1.249934 1.169924)
			(stroke
				(width 0.1)
				(type default)
			)
			(layer "F.Fab")
		)
		(fp_line
			(start -0.6985 0.729996)
			(end -1.249934 0.729996)
			(stroke
				(width 0.1)
				(type default)
			)
			(layer "F.Fab")
		)
		(fp_line
			(start 0.700024 0.219964)
			(end 1.249934 0.219964)
			(stroke
				(width 0.1)
				(type default)
			)
			(layer "F.Fab")
		)
		(fp_line
			(start 1.249934 0.219964)
			(end 1.249934 -0.219964)
			(stroke
				(width 0.1)
				(type default)
			)
			(layer "F.Fab")
		)
		(fp_line
			(start 0.700024 -0.219964)
			(end 0.700024 -1.500124)
			(stroke
				(width 0.1)
				(type default)
			)
			(layer "F.Fab")
		)
		(fp_line
			(start 1.249934 -0.219964)
			(end 0.700024 -0.219964)
			(stroke
				(width 0.1)
				(type default)
			)
			(layer "F.Fab")
		)
		(fp_line
			(start -1.249934 -0.729996)
			(end -0.6985 -0.729996)
			(stroke
				(width 0.1)
				(type default)
			)
			(layer "F.Fab")
		)
		(fp_line
			(start -0.6985 -0.729996)
			(end -0.6985 0.729996)
			(stroke
				(width 0.1)
				(type default)
			)
			(layer "F.Fab")
		)
		(fp_line
			(start -1.249934 -1.169924)
			(end -1.249934 -0.729996)
			(stroke
				(width 0.1)
				(type default)
			)
			(layer "F.Fab")
		)
		(fp_line
			(start -0.700024 -1.169924)
			(end -1.249934 -1.169924)
			(stroke
				(width 0.1)
				(type default)
			)
			(layer "F.Fab")
		)
		(fp_line
			(start -0.700024 -1.500124)
			(end -0.700024 -1.169924)
			(stroke
				(width 0.1)
				(type default)
			)
			(layer "F.Fab")
		)
		(fp_line
			(start 0.700024 -1.500124)
			(end -0.700024 -1.500124)
			(stroke
				(width 0.1)
				(type default)
			)
			(layer "F.Fab")
		)
		(fp_rect
			(start -0.700024 1.500124)
			(end 0.700024 -1.500124)
			(stroke
				(width 0)
				(type default)
			)
			(fill no)
			(layer "F.Fab")
		)
		(pad "D" smd rect
			(at 0.999998 0 180)
			(size 0.8128 0.9144)
			(layers "F.Cu" "F.Mask" "F.Paste")
			(net "HSC_EN")
		)
		(pad "G" smd rect
			(at -0.999998 -0.94996 180)
			(size 0.8128 0.9144)
			(layers "F.Cu" "F.Mask" "F.Paste")
			(net "PDB_PRSNT_R_N")
		)
		(pad "S" smd rect
			(at -0.999998 0.94996 180)
			(size 0.8128 0.9144)
			(layers "F.Cu" "F.Mask" "F.Paste")
			(net "GND")
		)
	)
)
